(kicad_pcb
	(version 20260206)
	(generator "pcbnew")
	(generator_version "10.0")
	(general
		(thickness 1.6)
		(legacy_teardrops no)
	)
	(paper "A4")
	(title_block
		(title "v1-chassis-manager — T6M_CM_d_v01_1031_1645.brd")
		(comment 1 "Open CloudServer (Microsoft) / footprints 1710-1719 of 2512")
	)
	(layers
		(0 "F.Cu" signal "TOP")
		(4 "In1.Cu" signal "GND1")
		(6 "In2.Cu" signal "IN1")
		(8 "In3.Cu" signal "VCC1")
		(10 "In4.Cu" signal "VCC2")
		(12 "In5.Cu" signal "GND2")
		(14 "In6.Cu" signal "IN2")
		(16 "In7.Cu" signal "IN3")
		(18 "In8.Cu" signal "GND3")
		(2 "B.Cu" signal "BOTTOM")
		(9 "F.Adhes" user "F.Adhesive")
		(11 "B.Adhes" user "B.Adhesive")
		(13 "F.Paste" user "Package Geometry/Pastemask Top")
		(15 "B.Paste" user "Package Geometry/Pastemask Bottom")
		(5 "F.SilkS" user "Ref Des/Silkscreen Top")
		(7 "B.SilkS" user "Ref Des/Silkscreen Bottom")
		(1 "F.Mask" user "Board Geometry/Soldermask Top")
		(3 "B.Mask" user "Board Geometry/Soldermask Bottom")
		(17 "Dwgs.User" user "User.Drawings")
		(19 "Cmts.User" user "User.Comments")
		(21 "Eco1.User" user "User.Eco1")
		(23 "Eco2.User" user "User.Eco2")
		(25 "Edge.Cuts" user "Board Geometry/Outline")
		(27 "Margin" user)
		(31 "F.CrtYd" user "Package Geometry/Place Bound Top")
		(29 "B.CrtYd" user "Package Geometry/Place Bound Bottom")
		(35 "F.Fab" user "Ref Des/Assembly Top")
		(33 "B.Fab" user "Ref Des/Assembly Bottom")
	)
	(footprint ""
		(layer "B.Cu")
		(at 159.501078 -181.995318 90)
		(property "Reference" "R1176"
			(at -0.921004 3.204972 270)
			(unlocked yes)
			(layer "B.SilkS")
			(effects
				(font
					(size 0.7874 0.5842)
					(thickness 0.1524)
				)
				(justify left mirror)
			)
		)
		(property "Value" ""
			(at 0 0 90)
			(layer "B.Fab")
			(effects
				(font
					(size 1.27 1.27)
				)
				(justify mirror)
			)
		)
		(duplicate_pad_numbers_are_jumpers no)
		(fp_line
			(start 0.7874 -0.4064)
			(end -0.7874 -0.4064)
			(stroke
				(width 0.1524)
				(type default)
			)
			(layer "B.SilkS")
		)
		(fp_line
			(start -0.7874 -0.4064)
			(end -0.7874 0.4064)
			(stroke
				(width 0.1524)
				(type default)
			)
			(layer "B.SilkS")
		)
		(fp_line
			(start 0.7874 0.4064)
			(end 0.7874 -0.4064)
			(stroke
				(width 0.1524)
				(type default)
			)
			(layer "B.SilkS")
		)
		(fp_line
			(start -0.7874 0.4064)
			(end 0.7874 0.4064)
			(stroke
				(width 0.1524)
				(type default)
			)
			(layer "B.SilkS")
		)
		(fp_poly
			(pts
				(xy 0.508 0.2794) (xy 0.508 0.2286) (xy 0.635 0.2286) (xy 0.635 -0.254) (xy 0.5334 -0.254) (xy 0.5334 -0.2794)
				(xy -0.5334 -0.2794) (xy -0.5334 -0.254) (xy -0.635 -0.254) (xy -0.635 0.254) (xy -0.5334 0.254)
				(xy -0.5334 0.2794)
			)
			(stroke
				(width 0)
				(type default)
			)
			(fill no)
			(layer "B.CrtYd")
		)
		(pad "1" smd rect
			(at -0.40005 0 270)
			(size 0.4572 0.508)
			(layers "B.Cu" "B.Mask" "B.Paste")
			(net "CPLD_UART_DTR_P4_R_N")
		)
		(pad "2" smd rect
			(at 0.40005 0 270)
			(size 0.4572 0.508)
			(layers "B.Cu" "B.Mask" "B.Paste")
			(net "CPLD_UART_DTR_P4_N")
		)
	)
	(footprint ""
		(layer "B.Cu")
		(at 142.07236 -168.949624)
		(property "Reference" "R734"
			(at -1.237234 0.53086 0)
			(unlocked yes)
			(layer "B.SilkS")
			(effects
				(font
					(size 0.7874 0.5842)
					(thickness 0.1524)
				)
				(justify left mirror)
			)
		)
		(property "Value" ""
			(at 0 0 0)
			(layer "B.Fab")
			(effects
				(font
					(size 1.27 1.27)
				)
				(justify mirror)
			)
		)
		(duplicate_pad_numbers_are_jumpers no)
		(fp_line
			(start -0.7874 -0.4064)
			(end -0.7874 0.4064)
			(stroke
				(width 0.1524)
				(type default)
			)
			(layer "B.SilkS")
		)
		(fp_line
			(start -0.7874 0.4064)
			(end 0.7874 0.4064)
			(stroke
				(width 0.1524)
				(type default)
			)
			(layer "B.SilkS")
		)
		(fp_line
			(start 0.7874 -0.4064)
			(end -0.7874 -0.4064)
			(stroke
				(width 0.1524)
				(type default)
			)
			(layer "B.SilkS")
		)
		(fp_line
			(start 0.7874 0.4064)
			(end 0.7874 -0.4064)
			(stroke
				(width 0.1524)
				(type default)
			)
			(layer "B.SilkS")
		)
		(fp_poly
			(pts
				(xy 0.508 0.2794) (xy 0.508 0.2286) (xy 0.635 0.2286) (xy 0.635 -0.254) (xy 0.5334 -0.254) (xy 0.5334 -0.2794)
				(xy -0.5334 -0.2794) (xy -0.5334 -0.254) (xy -0.635 -0.254) (xy -0.635 0.254) (xy -0.5334 0.254)
				(xy -0.5334 0.2794)
			)
			(stroke
				(width 0)
				(type default)
			)
			(fill no)
			(layer "B.CrtYd")
		)
		(pad "1" smd rect
			(at -0.40005 0 180)
			(size 0.4572 0.508)
			(layers "B.Cu" "B.Mask" "B.Paste")
			(net "P3V3_NODE1")
		)
		(pad "2" smd rect
			(at 0.40005 0 180)
			(size 0.4572 0.508)
			(layers "B.Cu" "B.Mask" "B.Paste")
			(net "N21700156")
		)
	)
	(footprint ""
		(layer "B.Cu")
		(at 57.38876 -185.205624 -90)
		(property "Reference" "C688"
			(at -4.15163 -0.146812 270)
			(unlocked yes)
			(layer "B.SilkS")
			(effects
				(font
					(size 0.7874 0.5842)
					(thickness 0.1524)
				)
				(justify left mirror)
			)
		)
		(property "Value" ""
			(at 0 0 90)
			(layer "B.Fab")
			(effects
				(font
					(size 1.27 1.27)
				)
				(justify mirror)
			)
		)
		(duplicate_pad_numbers_are_jumpers no)
		(fp_line
			(start -0.7874 0.4064)
			(end 0.7874 0.4064)
			(stroke
				(width 0.1524)
				(type default)
			)
			(layer "B.SilkS")
		)
		(fp_line
			(start 0.7874 0.4064)
			(end 0.7874 -0.4064)
			(stroke
				(width 0.1524)
				(type default)
			)
			(layer "B.SilkS")
		)
		(fp_line
			(start 0 0.381)
			(end 0 -0.381)
			(stroke
				(width 0.1524)
				(type default)
			)
			(layer "B.SilkS")
		)
		(fp_line
			(start -0.7874 -0.4064)
			(end -0.7874 0.4064)
			(stroke
				(width 0.1524)
				(type default)
			)
			(layer "B.SilkS")
		)
		(fp_line
			(start 0.7874 -0.4064)
			(end -0.7874 -0.4064)
			(stroke
				(width 0.1524)
				(type default)
			)
			(layer "B.SilkS")
		)
		(fp_poly
			(pts
				(xy 0.5334 0.254) (xy 0.635 0.254) (xy 0.635 0.2286) (xy 0.635 -0.254) (xy 0.5334 -0.254) (xy 0.5334 -0.2794)
				(xy -0.5334 -0.2794) (xy -0.5334 -0.254) (xy -0.635 -0.254) (xy -0.635 0.254) (xy -0.5334 0.254)
				(xy -0.5334 0.2794) (xy 0.508 0.2794) (xy 0.5334 0.2794)
			)
			(stroke
				(width 0)
				(type default)
			)
			(fill no)
			(layer "B.CrtYd")
		)
		(pad "1" smd rect
			(at -0.40005 0 90)
			(size 0.4572 0.508)
			(layers "B.Cu" "B.Mask" "B.Paste")
			(net "UART_T1_NODE4_RXD")
		)
		(pad "2" smd rect
			(at 0.40005 0 90)
			(size 0.4572 0.508)
			(layers "B.Cu" "B.Mask" "B.Paste")
			(net "GND")
		)
	)
	(footprint ""
		(layer "B.Cu")
		(at 121.40184 -141.388592 180)
		(property "Reference" "C187"
			(at 2.075942 -0.081534 0)
			(unlocked yes)
			(layer "B.SilkS")
			(effects
				(font
					(size 0.7874 0.5842)
					(thickness 0.1524)
				)
				(justify left mirror)
			)
		)
		(property "Value" ""
			(at 0 0 0)
			(layer "B.Fab")
			(effects
				(font
					(size 1.27 1.27)
				)
				(justify mirror)
			)
		)
		(duplicate_pad_numbers_are_jumpers no)
		(fp_line
			(start 0.7874 0.4064)
			(end 0.7874 -0.4064)
			(stroke
				(width 0.1524)
				(type default)
			)
			(layer "B.SilkS")
		)
		(fp_line
			(start 0.7874 -0.4064)
			(end -0.7874 -0.4064)
			(stroke
				(width 0.1524)
				(type default)
			)
			(layer "B.SilkS")
		)
		(fp_line
			(start 0 0.381)
			(end 0 -0.381)
			(stroke
				(width 0.1524)
				(type default)
			)
			(layer "B.SilkS")
		)
		(fp_line
			(start -0.7874 0.4064)
			(end 0.7874 0.4064)
			(stroke
				(width 0.1524)
				(type default)
			)
			(layer "B.SilkS")
		)
		(fp_line
			(start -0.7874 -0.4064)
			(end -0.7874 0.4064)
			(stroke
				(width 0.1524)
				(type default)
			)
			(layer "B.SilkS")
		)
		(fp_poly
			(pts
				(xy 0.5334 0.254) (xy 0.635 0.254) (xy 0.635 0.2286) (xy 0.635 -0.254) (xy 0.5334 -0.254) (xy 0.5334 -0.2794)
				(xy -0.5334 -0.2794) (xy -0.5334 -0.254) (xy -0.635 -0.254) (xy -0.635 0.254) (xy -0.5334 0.254)
				(xy -0.5334 0.2794) (xy 0.508 0.2794) (xy 0.5334 0.2794)
			)
			(stroke
				(width 0)
				(type default)
			)
			(fill no)
			(layer "B.CrtYd")
		)
		(pad "1" smd rect
			(at -0.40005 0)
			(size 0.4572 0.508)
			(layers "B.Cu" "B.Mask" "B.Paste")
			(net "P2E_CPU_BMC_NODE1_TX_C_DP")
		)
		(pad "2" smd rect
			(at 0.40005 0)
			(size 0.4572 0.508)
			(layers "B.Cu" "B.Mask" "B.Paste")
			(net "P2E_CPU_BMC_NODE1_TX_DP")
		)
	)
	(footprint ""
		(layer "B.Cu")
		(at 156.83738 -151.877522)
		(property "Reference" "C464"
			(at 1.076198 -1.312926 0)
			(unlocked yes)
			(layer "B.SilkS")
			(effects
				(font
					(size 0.7874 0.5842)
					(thickness 0.1524)
				)
				(justify left mirror)
			)
		)
		(property "Value" ""
			(at 0 0 0)
			(layer "B.Fab")
			(effects
				(font
					(size 1.27 1.27)
				)
				(justify mirror)
			)
		)
		(duplicate_pad_numbers_are_jumpers no)
		(fp_line
			(start -0.7874 -0.4064)
			(end -0.7874 0.4064)
			(stroke
				(width 0.1524)
				(type default)
			)
			(layer "B.SilkS")
		)
		(fp_line
			(start -0.7874 0.4064)
			(end 0.7874 0.4064)
			(stroke
				(width 0.1524)
				(type default)
			)
			(layer "B.SilkS")
		)
		(fp_line
			(start 0 0.381)
			(end 0 -0.381)
			(stroke
				(width 0.1524)
				(type default)
			)
			(layer "B.SilkS")
		)
		(fp_line
			(start 0.7874 -0.4064)
			(end -0.7874 -0.4064)
			(stroke
				(width 0.1524)
				(type default)
			)
			(layer "B.SilkS")
		)
		(fp_line
			(start 0.7874 0.4064)
			(end 0.7874 -0.4064)
			(stroke
				(width 0.1524)
				(type default)
			)
			(layer "B.SilkS")
		)
		(fp_poly
			(pts
				(xy 0.5334 0.254) (xy 0.635 0.254) (xy 0.635 0.2286) (xy 0.635 -0.254) (xy 0.5334 -0.254) (xy 0.5334 -0.2794)
				(xy -0.5334 -0.2794) (xy -0.5334 -0.254) (xy -0.635 -0.254) (xy -0.635 0.254) (xy -0.5334 0.254)
				(xy -0.5334 0.2794) (xy 0.508 0.2794) (xy 0.5334 0.2794)
			)
			(stroke
				(width 0)
				(type default)
			)
			(fill no)
			(layer "B.CrtYd")
		)
		(pad "1" smd rect
			(at -0.40005 0 180)
			(size 0.4572 0.508)
			(layers "B.Cu" "B.Mask" "B.Paste")
			(net "P1V05_LAN2")
		)
		(pad "2" smd rect
			(at 0.40005 0 180)
			(size 0.4572 0.508)
			(layers "B.Cu" "B.Mask" "B.Paste")
			(net "GND")
		)
	)
	(footprint ""
		(layer "B.Cu")
		(at 77.649832 -129.385822 -90)
		(property "Reference" "R1230"
			(at -1.60274 -0.09525 270)
			(unlocked yes)
			(layer "B.SilkS")
			(effects
				(font
					(size 0.7874 0.5842)
					(thickness 0.1524)
				)
				(justify left mirror)
			)
		)
		(property "Value" ""
			(at 0 0 90)
			(layer "B.Fab")
			(effects
				(font
					(size 1.27 1.27)
				)
				(justify mirror)
			)
		)
		(duplicate_pad_numbers_are_jumpers no)
		(fp_line
			(start -0.7874 0.4064)
			(end 0.7874 0.4064)
			(stroke
				(width 0.1524)
				(type default)
			)
			(layer "B.SilkS")
		)
		(fp_line
			(start 0.7874 0.4064)
			(end 0.7874 -0.4064)
			(stroke
				(width 0.1524)
				(type default)
			)
			(layer "B.SilkS")
		)
		(fp_line
			(start -0.7874 -0.4064)
			(end -0.7874 0.4064)
			(stroke
				(width 0.1524)
				(type default)
			)
			(layer "B.SilkS")
		)
		(fp_line
			(start 0.7874 -0.4064)
			(end -0.7874 -0.4064)
			(stroke
				(width 0.1524)
				(type default)
			)
			(layer "B.SilkS")
		)
		(fp_poly
			(pts
				(xy 0.508 0.2794) (xy 0.508 0.2286) (xy 0.635 0.2286) (xy 0.635 -0.254) (xy 0.5334 -0.254) (xy 0.5334 -0.2794)
				(xy -0.5334 -0.2794) (xy -0.5334 -0.254) (xy -0.635 -0.254) (xy -0.635 0.254) (xy -0.5334 0.254)
				(xy -0.5334 0.2794)
			)
			(stroke
				(width 0)
				(type default)
			)
			(fill no)
			(layer "B.CrtYd")
		)
		(pad "1" smd rect
			(at -0.40005 0 90)
			(size 0.4572 0.508)
			(layers "B.Cu" "B.Mask" "B.Paste")
			(net "GND")
		)
		(pad "2" smd rect
			(at 0.40005 0 90)
			(size 0.4572 0.508)
			(layers "B.Cu" "B.Mask" "B.Paste")
			(net "PD_BMC_LPC")
		)
	)
	(footprint ""
		(layer "B.Cu")
		(at 99.059746 -169.380662 -90)
		(property "Reference" "C766"
			(at 0.98552 1.899412 270)
			(unlocked yes)
			(layer "B.SilkS")
			(effects
				(font
					(size 0.7874 0.5842)
					(thickness 0.1524)
				)
				(justify left mirror)
			)
		)
		(property "Value" ""
			(at 0 0 90)
			(layer "B.Fab")
			(effects
				(font
					(size 1.27 1.27)
				)
				(justify mirror)
			)
		)
		(duplicate_pad_numbers_are_jumpers no)
		(fp_line
			(start -0.7874 0.4064)
			(end 0.7874 0.4064)
			(stroke
				(width 0.1524)
				(type default)
			)
			(layer "B.SilkS")
		)
		(fp_line
			(start 0.7874 0.4064)
			(end 0.7874 -0.4064)
			(stroke
				(width 0.1524)
				(type default)
			)
			(layer "B.SilkS")
		)
		(fp_line
			(start 0 0.381)
			(end 0 -0.381)
			(stroke
				(width 0.1524)
				(type default)
			)
			(layer "B.SilkS")
		)
		(fp_line
			(start -0.7874 -0.4064)
			(end -0.7874 0.4064)
			(stroke
				(width 0.1524)
				(type default)
			)
			(layer "B.SilkS")
		)
		(fp_line
			(start 0.7874 -0.4064)
			(end -0.7874 -0.4064)
			(stroke
				(width 0.1524)
				(type default)
			)
			(layer "B.SilkS")
		)
		(fp_poly
			(pts
				(xy 0.5334 0.254) (xy 0.635 0.254) (xy 0.635 0.2286) (xy 0.635 -0.254) (xy 0.5334 -0.254) (xy 0.5334 -0.2794)
				(xy -0.5334 -0.2794) (xy -0.5334 -0.254) (xy -0.635 -0.254) (xy -0.635 0.254) (xy -0.5334 0.254)
				(xy -0.5334 0.2794) (xy 0.508 0.2794) (xy 0.5334 0.2794)
			)
			(stroke
				(width 0)
				(type default)
			)
			(fill no)
			(layer "B.CrtYd")
		)
		(pad "1" smd rect
			(at -0.40005 0 90)
			(size 0.4572 0.508)
			(layers "B.Cu" "B.Mask" "B.Paste")
			(net "P3V3_NODE1")
		)
		(pad "2" smd rect
			(at 0.40005 0 90)
			(size 0.4572 0.508)
			(layers "B.Cu" "B.Mask" "B.Paste")
			(net "GND")
		)
	)
	(footprint ""
		(layer "B.Cu")
		(at 46.750732 -94.40037 -90)
		(property "Reference" "C27"
			(at 4.703318 4.403852 270)
			(unlocked yes)
			(layer "B.SilkS")
			(effects
				(font
					(size 0.7874 0.5842)
					(thickness 0.1524)
				)
				(justify left mirror)
			)
		)
		(property "Value" ""
			(at 0 0 90)
			(layer "B.Fab")
			(effects
				(font
					(size 1.27 1.27)
				)
				(justify mirror)
			)
		)
		(duplicate_pad_numbers_are_jumpers no)
		(fp_line
			(start -0.7874 0.4064)
			(end 0.7874 0.4064)
			(stroke
				(width 0.1524)
				(type default)
			)
			(layer "B.SilkS")
		)
		(fp_line
			(start 0.7874 0.4064)
			(end 0.7874 -0.4064)
			(stroke
				(width 0.1524)
				(type default)
			)
			(layer "B.SilkS")
		)
		(fp_line
			(start 0 0.381)
			(end 0 -0.381)
			(stroke
				(width 0.1524)
				(type default)
			)
			(layer "B.SilkS")
		)
		(fp_line
			(start -0.7874 -0.4064)
			(end -0.7874 0.4064)
			(stroke
				(width 0.1524)
				(type default)
			)
			(layer "B.SilkS")
		)
		(fp_line
			(start 0.7874 -0.4064)
			(end -0.7874 -0.4064)
			(stroke
				(width 0.1524)
				(type default)
			)
			(layer "B.SilkS")
		)
		(fp_poly
			(pts
				(xy 0.5334 0.254) (xy 0.635 0.254) (xy 0.635 0.2286) (xy 0.635 -0.254) (xy 0.5334 -0.254) (xy 0.5334 -0.2794)
				(xy -0.5334 -0.2794) (xy -0.5334 -0.254) (xy -0.635 -0.254) (xy -0.635 0.254) (xy -0.5334 0.254)
				(xy -0.5334 0.2794) (xy 0.508 0.2794) (xy 0.5334 0.2794)
			)
			(stroke
				(width 0)
				(type default)
			)
			(fill no)
			(layer "B.CrtYd")
		)
		(pad "1" smd rect
			(at -0.40005 0 90)
			(size 0.4572 0.508)
			(layers "B.Cu" "B.Mask" "B.Paste")
			(net "GND")
		)
		(pad "2" smd rect
			(at 0.40005 0 90)
			(size 0.4572 0.508)
			(layers "B.Cu" "B.Mask" "B.Paste")
			(net "SMB_CPU_NODE1_XDP_DAT_R")
		)
	)
	(footprint ""
		(layer "B.Cu")
		(at 154.620214 -62.075822 -90)
		(property "Reference" "C355"
			(at 2.829814 -6.081268 270)
			(unlocked yes)
			(layer "B.SilkS")
			(effects
				(font
					(size 0.7874 0.5842)
					(thickness 0.1524)
				)
				(justify left mirror)
			)
		)
		(property "Value" ""
			(at 0 0 90)
			(layer "B.Fab")
			(effects
				(font
					(size 1.27 1.27)
				)
				(justify mirror)
			)
		)
		(duplicate_pad_numbers_are_jumpers no)
		(fp_line
			(start -0.7874 0.4064)
			(end 0.7874 0.4064)
			(stroke
				(width 0.1524)
				(type default)
			)
			(layer "B.SilkS")
		)
		(fp_line
			(start 0.7874 0.4064)
			(end 0.7874 -0.4064)
			(stroke
				(width 0.1524)
				(type default)
			)
			(layer "B.SilkS")
		)
		(fp_line
			(start 0 0.381)
			(end 0 -0.381)
			(stroke
				(width 0.1524)
				(type default)
			)
			(layer "B.SilkS")
		)
		(fp_line
			(start -0.7874 -0.4064)
			(end -0.7874 0.4064)
			(stroke
				(width 0.1524)
				(type default)
			)
			(layer "B.SilkS")
		)
		(fp_line
			(start 0.7874 -0.4064)
			(end -0.7874 -0.4064)
			(stroke
				(width 0.1524)
				(type default)
			)
			(layer "B.SilkS")
		)
		(fp_poly
			(pts
				(xy 0.5334 0.254) (xy 0.635 0.254) (xy 0.635 0.2286) (xy 0.635 -0.254) (xy 0.5334 -0.254) (xy 0.5334 -0.2794)
				(xy -0.5334 -0.2794) (xy -0.5334 -0.254) (xy -0.635 -0.254) (xy -0.635 0.254) (xy -0.5334 0.254)
				(xy -0.5334 0.2794) (xy 0.508 0.2794) (xy 0.5334 0.2794)
			)
			(stroke
				(width 0)
				(type default)
			)
			(fill no)
			(layer "B.CrtYd")
		)
		(pad "1" smd rect
			(at -0.40005 0 90)
			(size 0.4572 0.508)
			(layers "B.Cu" "B.Mask" "B.Paste")
			(net "P1V8_SATA_VAA2_1_NODE1")
		)
		(pad "2" smd rect
			(at 0.40005 0 90)
			(size 0.4572 0.508)
			(layers "B.Cu" "B.Mask" "B.Paste")
			(net "GND")
		)
	)
	(footprint ""
		(layer "B.Cu")
		(at 135.196834 -34.327084)
		(property "Reference" "R1185"
			(at -5.415788 18.52295 0)
			(unlocked yes)
			(layer "B.SilkS")
			(effects
				(font
					(size 0.7874 0.5842)
					(thickness 0.1524)
				)
				(justify left mirror)
			)
		)
		(property "Value" ""
			(at 0 0 0)
			(layer "B.Fab")
			(effects
				(font
					(size 1.27 1.27)
				)
				(justify mirror)
			)
		)
		(duplicate_pad_numbers_are_jumpers no)
		(fp_line
			(start -0.7874 -0.4064)
			(end -0.7874 0.4064)
			(stroke
				(width 0.1524)
				(type default)
			)
			(layer "B.SilkS")
		)
		(fp_line
			(start -0.7874 0.4064)
			(end 0.7874 0.4064)
			(stroke
				(width 0.1524)
				(type default)
			)
			(layer "B.SilkS")
		)
		(fp_line
			(start 0.7874 -0.4064)
			(end -0.7874 -0.4064)
			(stroke
				(width 0.1524)
				(type default)
			)
			(layer "B.SilkS")
		)
		(fp_line
			(start 0.7874 0.4064)
			(end 0.7874 -0.4064)
			(stroke
				(width 0.1524)
				(type default)
			)
			(layer "B.SilkS")
		)
		(fp_poly
			(pts
				(xy 0.508 0.2794) (xy 0.508 0.2286) (xy 0.635 0.2286) (xy 0.635 -0.254) (xy 0.5334 -0.254) (xy 0.5334 -0.2794)
				(xy -0.5334 -0.2794) (xy -0.5334 -0.254) (xy -0.635 -0.254) (xy -0.635 0.254) (xy -0.5334 0.254)
				(xy -0.5334 0.2794)
			)
			(stroke
				(width 0)
				(type default)
			)
			(fill no)
			(layer "B.CrtYd")
		)
		(pad "1" smd rect
			(at -0.40005 0 180)
			(size 0.4572 0.508)
			(layers "B.Cu" "B.Mask" "B.Paste")
			(net "CPLD123_RSV3")
		)
		(pad "2" smd rect
			(at 0.40005 0 180)
			(size 0.4572 0.508)
			(layers "B.Cu" "B.Mask" "B.Paste")
			(net "SIO_CPLD_RSV3_R")
		)
	)
)
